(kicad_pcb
	(version 20241229)
	(generator "pcbnew")
	(generator_version "9.0")
	(general
		(thickness 1.711)
		(legacy_teardrops no)
	)
	(paper "A4")
	(title_block
		(title "Antmicro Baseboard for Jetson AGX Thor")
		(date "2026-02-18")
		(rev "1.1.0")
		(company "Antmicro Ltd")
		(comment 1 "www.antmicro.com")
		(comment 9 "footprints 901-905 of 1170")
	)
	(layers
		(0 "F.Cu" signal)
		(4 "In1.Cu" signal)
		(6 "In2.Cu" signal)
		(8 "In3.Cu" signal)
		(10 "In4.Cu" jumper)
		(12 "In5.Cu" signal)
		(14 "In6.Cu" signal)
		(16 "In7.Cu" signal)
		(18 "In8.Cu" signal)
		(2 "B.Cu" signal)
		(9 "F.Adhes" user "F.Adhesive")
		(11 "B.Adhes" user "B.Adhesive")
		(13 "F.Paste" user)
		(15 "B.Paste" user)
		(5 "F.SilkS" user "F.Silkscreen")
		(7 "B.SilkS" user "B.Silkscreen")
		(1 "F.Mask" user)
		(3 "B.Mask" user)
		(17 "Dwgs.User" user "User.Drawings")
		(19 "Cmts.User" user "User.Comments")
		(21 "Eco1.User" user "User.Eco1")
		(23 "Eco2.User" user "User.Eco2")
		(25 "Edge.Cuts" user)
		(27 "Margin" user)
		(31 "F.CrtYd" user "F.Courtyard")
		(29 "B.CrtYd" user "B.Courtyard")
		(35 "F.Fab" user)
		(33 "B.Fab" user)
	)
	(footprint "antmicro-footprints:C_0402_1005Metric"
		(layer "B.Cu")
		(at 119.78 70.59 180)
		(descr "Capacitor SMD 0402")
		(tags "capacitor SMD 0402")
		(property "Reference" "C17"
			(at -1.42 -3.11 0)
			(layer "B.SilkS")
			(effects
				(font
					(size 0.7 0.7)
					(thickness 0.15)
				)
				(justify left bottom mirror)
			)
		)
		(property "Value" "C_100n_0402"
			(at -1.022927 -2.155213 0)
			(layer "B.Fab")
			(effects
				(font
					(size 0.7 0.7)
					(thickness 0.15)
				)
				(justify left bottom mirror)
			)
		)
		(property "Datasheet" "https://www.murata.com/products/productdetail?partno=GRM155R61H104KE14%23"
			(at 0 0 0)
			(layer "B.Fab")
			(hide yes)
			(effects
				(font
					(size 1.27 1.27)
					(thickness 0.15)
				)
				(justify mirror)
			)
		)
		(property "Description" "SMD Multilayer Ceramic Capacitor, 0.1 µF, 50 V, 0402 [1005 Metric], ± 10%, X5R, GRM Series"
			(at 0 0 0)
			(layer "B.Fab")
			(hide yes)
			(effects
				(font
					(size 1.27 1.27)
					(thickness 0.15)
				)
				(justify mirror)
			)
		)
		(property "MPN" "GRM155R61H104KE14D"
			(at 0 0 0)
			(unlocked yes)
			(layer "B.Fab")
			(hide yes)
			(effects
				(font
					(size 1 1)
					(thickness 0.15)
				)
				(justify mirror)
			)
		)
		(property "Val" "100n"
			(at 0 0 0)
			(unlocked yes)
			(layer "B.Fab")
			(hide yes)
			(effects
				(font
					(size 1 1)
					(thickness 0.15)
				)
				(justify mirror)
			)
		)
		(property "Voltage" "50V"
			(at 0 0 0)
			(unlocked yes)
			(layer "B.Fab")
			(hide yes)
			(effects
				(font
					(size 1 1)
					(thickness 0.15)
				)
				(justify mirror)
			)
		)
		(property "Dielectric" "X5R"
			(at 0 0 0)
			(unlocked yes)
			(layer "B.Fab")
			(hide yes)
			(effects
				(font
					(size 1 1)
					(thickness 0.15)
				)
				(justify mirror)
			)
		)
		(property "Manufacturer" "Murata"
			(at 0 0 0)
			(unlocked yes)
			(layer "B.Fab")
			(hide yes)
			(effects
				(font
					(size 1 1)
					(thickness 0.15)
				)
				(justify mirror)
			)
		)
		(property "License" "Apache-2.0"
			(at 0 0 0)
			(unlocked yes)
			(layer "B.Fab")
			(hide yes)
			(effects
				(font
					(size 1 1)
					(thickness 0.15)
				)
				(justify mirror)
			)
		)
		(property "Author" "Antmicro"
			(at 0 0 0)
			(unlocked yes)
			(layer "B.Fab")
			(hide yes)
			(effects
				(font
					(size 1 1)
					(thickness 0.15)
				)
				(justify mirror)
			)
		)
		(sheetname "/SoM_Power/")
		(sheetfile "som_power.kicad_sch")
		(attr smd)
		(fp_rect
			(start -0.925 0.47)
			(end 0.925 -0.47)
			(stroke
				(width 0.05)
				(type default)
			)
			(fill no)
			(layer "B.CrtYd")
		)
		(fp_line
			(start 0.504 0.25)
			(end 0.504 -0.248)
			(stroke
				(width 0.15)
				(type solid)
			)
			(layer "B.Fab")
		)
		(fp_line
			(start 0.504 -0.248)
			(end -0.494 -0.248)
			(stroke
				(width 0.15)
				(type solid)
			)
			(layer "B.Fab")
		)
		(fp_line
			(start -0.494 0.25)
			(end 0.504 0.25)
			(stroke
				(width 0.15)
				(type solid)
			)
			(layer "B.Fab")
		)
		(fp_line
			(start -0.494 -0.248)
			(end -0.494 0.25)
			(stroke
				(width 0.15)
				(type solid)
			)
			(layer "B.Fab")
		)
		(fp_text user "License: Apache-2.0"
			(at -0.939 -5.799 0)
			(layer "B.Fab")
			(effects
				(font
					(size 0.7 0.7)
					(thickness 0.15)
				)
				(justify left bottom mirror)
			)
		)
		(fp_text user "${REFERENCE}"
			(at -0.939 -4.599 0)
			(layer "B.Fab")
			(effects
				(font
					(size 0.7 0.7)
					(thickness 0.15)
				)
				(justify left bottom mirror)
			)
		)
		(fp_text user "Author: Antmicro"
			(at -0.939 -3.399 0)
			(layer "B.Fab")
			(effects
				(font
					(size 0.7 0.7)
					(thickness 0.15)
				)
				(justify left bottom mirror)
			)
		)
		(pad "1" smd roundrect
			(at -0.48 0 180)
			(size 0.59 0.64)
			(layers "B.Cu" "B.Mask" "B.Paste")
			(roundrect_rratio 0.25)
			(net 1 "GND")
			(pintype "passive")
		)
		(pad "2" smd roundrect
			(at 0.48 0 180)
			(size 0.59 0.64)
			(layers "B.Cu" "B.Mask" "B.Paste")
			(roundrect_rratio 0.25)
			(net 213 "+5V_SOM")
			(pintype "passive")
		)
	)
	(footprint "antmicro-footprints:R_0402_1005Metric"
		(layer "B.Cu")
		(at 206.7 120 180)
		(descr "Resistor SMD 0402")
		(tags "resistor SMD 0402")
		(property "Reference" "R262"
			(at -3.86 -0.38 0)
			(layer "B.SilkS")
			(effects
				(font
					(size 0.7 0.7)
					(thickness 0.15)
				)
				(justify left bottom mirror)
			)
		)
		(property "Value" "R_49k9_0402"
			(at -1.011843 -1.772047 0)
			(layer "B.Fab")
			(effects
				(font
					(size 0.7 0.7)
					(thickness 0.15)
				)
				(justify left bottom mirror)
			)
		)
		(property "Datasheet" "https://www.bourns.com/docs/product-datasheets/cr.pdf"
			(at 0 0 0)
			(layer "B.Fab")
			(hide yes)
			(effects
				(font
					(size 1.27 1.27)
					(thickness 0.15)
				)
				(justify mirror)
			)
		)
		(property "Description" "SMD Chip Resistor, 49.9 kohm, ± 1%, 63 mW, 0402 [1005 Metric], Thick Film, General Purpose"
			(at 0 0 0)
			(layer "B.Fab")
			(hide yes)
			(effects
				(font
					(size 1.27 1.27)
					(thickness 0.15)
				)
				(justify mirror)
			)
		)
		(property "MPN" "CR0402-FX-4992GLF"
			(at 0 0 0)
			(unlocked yes)
			(layer "B.Fab")
			(hide yes)
			(effects
				(font
					(size 1 1)
					(thickness 0.15)
				)
				(justify mirror)
			)
		)
		(property "Manufacturer" "Bourns"
			(at 0 0 0)
			(unlocked yes)
			(layer "B.Fab")
			(hide yes)
			(effects
				(font
					(size 1 1)
					(thickness 0.15)
				)
				(justify mirror)
			)
		)
		(property "License" "Apache-2.0"
			(at 0 0 0)
			(unlocked yes)
			(layer "B.Fab")
			(hide yes)
			(effects
				(font
					(size 1 1)
					(thickness 0.15)
				)
				(justify mirror)
			)
		)
		(property "Author" "Antmicro"
			(at 0 0 0)
			(unlocked yes)
			(layer "B.Fab")
			(hide yes)
			(effects
				(font
					(size 1 1)
					(thickness 0.15)
				)
				(justify mirror)
			)
		)
		(property "Val" "49k9"
			(at 0 0 0)
			(unlocked yes)
			(layer "B.Fab")
			(hide yes)
			(effects
				(font
					(size 1 1)
					(thickness 0.15)
				)
				(justify mirror)
			)
		)
		(property "Tolerance" "1%"
			(at 0 0 0)
			(unlocked yes)
			(layer "B.Fab")
			(hide yes)
			(effects
				(font
					(size 1 1)
					(thickness 0.15)
				)
				(justify mirror)
			)
		)
		(sheetname "/USB Hub/")
		(sheetfile "usb_hub.kicad_sch")
		(attr smd)
		(fp_rect
			(start -0.925 0.47)
			(end 0.925 -0.47)
			(stroke
				(width 0.05)
				(type default)
			)
			(fill no)
			(layer "B.CrtYd")
		)
		(fp_rect
			(start -0.5 0.25)
			(end 0.5 -0.25)
			(stroke
				(width 0.15)
				(type solid)
			)
			(fill no)
			(layer "B.Fab")
		)
		(fp_text user "License: Apache-2.0"
			(at -0.95 -5.169 0)
			(layer "B.Fab")
			(effects
				(font
					(size 0.7 0.7)
					(thickness 0.15)
				)
				(justify left bottom mirror)
			)
		)
		(fp_text user "Author: Antmicro"
			(at -0.95 -4.169 0)
			(layer "B.Fab")
			(effects
				(font
					(size 0.7 0.7)
					(thickness 0.15)
				)
				(justify left bottom mirror)
			)
		)
		(fp_text user "${REFERENCE}"
			(at -0.95 -3.168 0)
			(layer "B.Fab")
			(effects
				(font
					(size 0.7 0.7)
					(thickness 0.15)
				)
				(justify left bottom mirror)
			)
		)
		(pad "1" smd roundrect
			(at -0.48 0 180)
			(size 0.59 0.64)
			(layers "B.Cu" "B.Mask" "B.Paste")
			(roundrect_rratio 0.25)
			(net 1 "GND")
			(pintype "passive")
		)
		(pad "2" smd roundrect
			(at 0.48 0 180)
			(size 0.59 0.64)
			(layers "B.Cu" "B.Mask" "B.Paste")
			(roundrect_rratio 0.25)
			(net 1016 "/USB Hub/USBC3_VBUS_MON")
			(pintype "passive")
		)
	)
	(footprint "antmicro-footprints:TP_SMD_0.75mm"
		(layer "B.Cu")
		(at 120.43 65.06 -90)
		(property "Reference" "TP85"
			(at 0.5 0.6 0)
			(layer "B.SilkS")
			(effects
				(font
					(size 0.7 0.7)
					(thickness 0.15)
				)
				(justify left bottom mirror)
			)
		)
		(property "Value" "TP_0.75mm_SMD"
			(at 0 -1.2 90)
			(layer "B.Fab")
			(effects
				(font
					(size 0.7 0.7)
					(thickness 0.15)
				)
				(justify left bottom mirror)
			)
		)
		(property "Description" "SMT test point"
			(at 0 0 90)
			(layer "B.Fab")
			(hide yes)
			(effects
				(font
					(size 1.27 1.27)
					(thickness 0.15)
				)
				(justify mirror)
			)
		)
		(property "MPN" ""
			(at 0 0 90)
			(unlocked yes)
			(layer "B.Fab")
			(hide yes)
			(effects
				(font
					(size 1 1)
					(thickness 0.15)
				)
				(justify mirror)
			)
		)
		(property "Manufacturer" ""
			(at 0 0 90)
			(unlocked yes)
			(layer "B.Fab")
			(hide yes)
			(effects
				(font
					(size 1 1)
					(thickness 0.15)
				)
				(justify mirror)
			)
		)
		(property "Author" "Antmicro"
			(at 0 0 90)
			(unlocked yes)
			(layer "B.Fab")
			(hide yes)
			(effects
				(font
					(size 1 1)
					(thickness 0.15)
				)
				(justify mirror)
			)
		)
		(property "License" "Apache-2.0"
			(at 0 0 90)
			(unlocked yes)
			(layer "B.Fab")
			(hide yes)
			(effects
				(font
					(size 1 1)
					(thickness 0.15)
				)
				(justify mirror)
			)
		)
		(sheetname "/SoM_Power/")
		(sheetfile "som_power.kicad_sch")
		(attr exclude_from_pos_files exclude_from_bom)
		(fp_circle
			(center 0 0)
			(end 0.475 0)
			(stroke
				(width 0.05)
				(type default)
			)
			(fill no)
			(layer "B.CrtYd")
		)
		(fp_text user "${REFERENCE}"
			(at -0.4 -2.7 90)
			(layer "B.Fab")
			(effects
				(font
					(size 0.7 0.7)
					(thickness 0.15)
				)
				(justify left bottom mirror)
			)
		)
		(fp_text user "License: Apache-2.0"
			(at -0.4 -5.101 90)
			(layer "B.Fab")
			(effects
				(font
					(size 0.7 0.7)
					(thickness 0.15)
				)
				(justify left bottom mirror)
			)
		)
		(fp_text user "Author: Antmicro"
			(at -0.4 -3.901 90)
			(layer "B.Fab")
			(effects
				(font
					(size 0.7 0.7)
					(thickness 0.15)
				)
				(justify left bottom mirror)
			)
		)
		(pad "1" smd circle
			(at 0 0 270)
			(size 0.75 0.75)
			(layers "B.Cu" "B.Mask")
			(net 246 "/SoM_Power/~{VDDIN_PWR_BAD}")
			(pinfunction "1")
			(pintype "passive")
		)
	)
	(footprint "antmicro-footprints:C_0402_1005Metric"
		(layer "B.Cu")
		(at 198.476 146.25 90)
		(descr "Capacitor SMD 0402")
		(tags "capacitor SMD 0402")
		(property "Reference" "C171"
			(at -1.55 -1.45 90)
			(layer "B.SilkS")
			(effects
				(font
					(size 0.7 0.7)
					(thickness 0.15)
				)
				(justify right top mirror)
			)
		)
		(property "Value" "C_100n_0402"
			(at -1.022927 -2.155213 90)
			(layer "B.Fab")
			(effects
				(font
					(size 0.7 0.7)
					(thickness 0.15)
				)
				(justify right top mirror)
			)
		)
		(property "Datasheet" "https://www.murata.com/products/productdetail?partno=GRM155R61H104KE14%23"
			(at 0 0 90)
			(layer "B.Fab")
			(hide yes)
			(effects
				(font
					(size 1.27 1.27)
					(thickness 0.15)
				)
				(justify mirror)
			)
		)
		(property "Description" "SMD Multilayer Ceramic Capacitor, 0.1 µF, 50 V, 0402 [1005 Metric], ± 10%, X5R, GRM Series"
			(at 0 0 90)
			(layer "B.Fab")
			(hide yes)
			(effects
				(font
					(size 1.27 1.27)
					(thickness 0.15)
				)
				(justify mirror)
			)
		)
		(property "MPN" "GRM155R61H104KE14D"
			(at 0 0 270)
			(unlocked yes)
			(layer "B.Fab")
			(hide yes)
			(effects
				(font
					(size 1 1)
					(thickness 0.15)
				)
				(justify mirror)
			)
		)
		(property "Manufacturer" "Murata"
			(at 0 0 270)
			(unlocked yes)
			(layer "B.Fab")
			(hide yes)
			(effects
				(font
					(size 1 1)
					(thickness 0.15)
				)
				(justify mirror)
			)
		)
		(property "License" "Apache-2.0"
			(at 0 0 270)
			(unlocked yes)
			(layer "B.Fab")
			(hide yes)
			(effects
				(font
					(size 1 1)
					(thickness 0.15)
				)
				(justify mirror)
			)
		)
		(property "Author" "Antmicro"
			(at 0 0 270)
			(unlocked yes)
			(layer "B.Fab")
			(hide yes)
			(effects
				(font
					(size 1 1)
					(thickness 0.15)
				)
				(justify mirror)
			)
		)
		(property "Val" "100n"
			(at 0 0 270)
			(unlocked yes)
			(layer "B.Fab")
			(hide yes)
			(effects
				(font
					(size 1 1)
					(thickness 0.15)
				)
				(justify mirror)
			)
		)
		(property "Voltage" "50V"
			(at 0 0 270)
			(unlocked yes)
			(layer "B.Fab")
			(hide yes)
			(effects
				(font
					(size 1 1)
					(thickness 0.15)
				)
				(justify mirror)
			)
		)
		(property "Dielectric" "X5R"
			(at 0 0 270)
			(unlocked yes)
			(layer "B.Fab")
			(hide yes)
			(effects
				(font
					(size 1 1)
					(thickness 0.15)
				)
				(justify mirror)
			)
		)
		(sheetname "/SFP/")
		(sheetfile "sfp.kicad_sch")
		(attr smd)
		(fp_poly
			(pts
				(xy -0.925 0.47) (xy 0.925 0.47) (xy 0.925 -0.47) (xy -0.925 -0.47)
			)
			(stroke
				(width 0.05)
				(type default)
			)
			(fill no)
			(layer "B.CrtYd")
		)
		(fp_line
			(start 0.504 -0.248)
			(end -0.494 -0.248)
			(stroke
				(width 0.15)
				(type solid)
			)
			(layer "B.Fab")
		)
		(fp_line
			(start -0.494 -0.248)
			(end -0.494 0.25)
			(stroke
				(width 0.15)
				(type solid)
			)
			(layer "B.Fab")
		)
		(fp_line
			(start 0.504 0.25)
			(end 0.504 -0.248)
			(stroke
				(width 0.15)
				(type solid)
			)
			(layer "B.Fab")
		)
		(fp_line
			(start -0.494 0.25)
			(end 0.504 0.25)
			(stroke
				(width 0.15)
				(type solid)
			)
			(layer "B.Fab")
		)
		(fp_text user "${REFERENCE}"
			(at -0.939 -4.599 90)
			(layer "B.Fab")
			(effects
				(font
					(size 0.7 0.7)
					(thickness 0.15)
				)
				(justify right top mirror)
			)
		)
		(fp_text user "Author: Antmicro"
			(at -0.939 -3.399 90)
			(layer "B.Fab")
			(effects
				(font
					(size 0.7 0.7)
					(thickness 0.15)
				)
				(justify right top mirror)
			)
		)
		(fp_text user "License: Apache-2.0"
			(at -0.939 -5.799 90)
			(layer "B.Fab")
			(effects
				(font
					(size 0.7 0.7)
					(thickness 0.15)
				)
				(justify right top mirror)
			)
		)
		(pad "1" smd roundrect
			(at -0.48 0 90)
			(size 0.59 0.64)
			(layers "B.Cu" "B.Mask" "B.Paste")
			(roundrect_rratio 0.25)
			(net 1 "GND")
			(pintype "passive")
		)
		(pad "2" smd roundrect
			(at 0.48 0 90)
			(size 0.59 0.64)
			(layers "B.Cu" "B.Mask" "B.Paste")
			(roundrect_rratio 0.25)
			(net 2 "+3V3")
			(pintype "passive")
		)
	)
	(footprint "antmicro-footprints:R_0402_1005Metric"
		(layer "B.Cu")
		(at 203.3 130.5 90)
		(descr "Resistor SMD 0402")
		(tags "resistor SMD 0402")
		(property "Reference" "R46"
			(at -3.1 -0.3 90)
			(layer "B.SilkS")
			(effects
				(font
					(size 0.7 0.7)
					(thickness 0.15)
				)
				(justify right top mirror)
			)
		)
		(property "Value" "R_0R_0402"
			(at -1.011843 -1.772047 90)
			(layer "B.Fab")
			(effects
				(font
					(size 0.7 0.7)
					(thickness 0.15)
				)
				(justify right top mirror)
			)
		)
		(property "Datasheet" "https://industrial.panasonic.com/cdbs/www-data/pdf/RDA0000/AOA0000C301.pdf"
			(at 0 0 90)
			(layer "B.Fab")
			(hide yes)
			(effects
				(font
					(size 1.27 1.27)
					(thickness 0.15)
				)
				(justify mirror)
			)
		)
		(property "Description" "SMD Chip Resistor, Jumper, 0 ohm, 100 mW, 0402 [1005 Metric], Thick Film, General Purpose"
			(at 0 0 90)
			(layer "B.Fab")
			(hide yes)
			(effects
				(font
					(size 1.27 1.27)
					(thickness 0.15)
				)
				(justify mirror)
			)
		)
		(property "Manufacturer" "Panasonic"
			(at 0 0 270)
			(unlocked yes)
			(layer "B.Fab")
			(hide yes)
			(effects
				(font
					(size 1 1)
					(thickness 0.15)
				)
				(justify mirror)
			)
		)
		(property "MPN" "ERJ2GE0R00X"
			(at 0 0 270)
			(unlocked yes)
			(layer "B.Fab")
			(hide yes)
			(effects
				(font
					(size 1 1)
					(thickness 0.15)
				)
				(justify mirror)
			)
		)
		(property "Val" "0R"
			(at 0 0 270)
			(unlocked yes)
			(layer "B.Fab")
			(hide yes)
			(effects
				(font
					(size 1 1)
					(thickness 0.15)
				)
				(justify mirror)
			)
		)
		(property "License" "Apache-2.0"
			(at 0 0 270)
			(unlocked yes)
			(layer "B.Fab")
			(hide yes)
			(effects
				(font
					(size 1 1)
					(thickness 0.15)
				)
				(justify mirror)
			)
		)
		(property "Author" "Antmicro"
			(at 0 0 270)
			(unlocked yes)
			(layer "B.Fab")
			(hide yes)
			(effects
				(font
					(size 1 1)
					(thickness 0.15)
				)
				(justify mirror)
			)
		)
		(property "Tolerance" "~"
			(at 0 0 270)
			(unlocked yes)
			(layer "B.Fab")
			(hide yes)
			(effects
				(font
					(size 1 1)
					(thickness 0.15)
				)
				(justify mirror)
			)
		)
		(property "Current" "1A"
			(at 0 0 270)
			(unlocked yes)
			(layer "B.Fab")
			(hide yes)
			(effects
				(font
					(size 1 1)
					(thickness 0.15)
				)
				(justify mirror)
			)
		)
		(sheetname "/USB Hub/")
		(sheetfile "usb_hub.kicad_sch")
		(attr smd)
		(fp_rect
			(start -0.925 0.47)
			(end 0.925 -0.47)
			(stroke
				(width 0.05)
				(type default)
			)
			(fill no)
			(layer "B.CrtYd")
		)
		(fp_rect
			(start -0.5 0.25)
			(end 0.5 -0.25)
			(stroke
				(width 0.15)
				(type solid)
			)
			(fill no)
			(layer "B.Fab")
		)
		(fp_text user "Author: Antmicro"
			(at -0.95 -4.169 90)
			(layer "B.Fab")
			(effects
				(font
					(size 0.7 0.7)
					(thickness 0.15)
				)
				(justify right top mirror)
			)
		)
		(fp_text user "License: Apache-2.0"
			(at -0.95 -5.169 90)
			(layer "B.Fab")
			(effects
				(font
					(size 0.7 0.7)
					(thickness 0.15)
				)
				(justify right top mirror)
			)
		)
		(fp_text user "${REFERENCE}"
			(at -0.95 -3.168 90)
			(layer "B.Fab")
			(effects
				(font
					(size 0.7 0.7)
					(thickness 0.15)
				)
				(justify right top mirror)
			)
		)
		(pad "1" smd roundrect
			(at -0.48 0 90)
			(size 0.59 0.64)
			(layers "B.Cu" "B.Mask" "B.Paste")
			(roundrect_rratio 0.25)
			(net 1126 "Net-(U21-USB2DN_DM3)")
			(pintype "passive")
		)
		(pad "2" smd roundrect
			(at 0.48 0 90)
			(size 0.59 0.64)
			(layers "B.Cu" "B.Mask" "B.Paste")
			(roundrect_rratio 0.25)
			(net 2 "+3V3")
			(pintype "passive")
		)
	)
)
